(kicad_pcb
	(version 20260206)
	(generator "pcbnew")
	(generator_version "10.0")
	(general
		(thickness 1.6)
		(legacy_teardrops no)
	)
	(paper "A4")
	(title_block
		(title "Bryce Canyon_IOM_IOC_16318-2_OCP.brd")
		(comment 1 "Bryce Canyon / footprints 869-873 of 1605")
	)
	(layers
		(0 "F.Cu" signal "TOP")
		(4 "In1.Cu" signal "L2GND")
		(6 "In2.Cu" signal "L3")
		(8 "In3.Cu" signal "L4VCC")
		(10 "In4.Cu" signal "L5VCC")
		(12 "In5.Cu" signal "L6")
		(14 "In6.Cu" signal "L7GND")
		(2 "B.Cu" signal "BOTTOM")
		(9 "F.Adhes" user "F.Adhesive")
		(11 "B.Adhes" user "B.Adhesive")
		(13 "F.Paste" user "Package Geometry/Pastemask Top")
		(15 "B.Paste" user "Package Geometry/Pastemask Bottom")
		(5 "F.SilkS" user "Ref Des/Silkscreen Top")
		(7 "B.SilkS" user "Ref Des/Silkscreen Bottom")
		(1 "F.Mask" user "Board Geometry/Soldermask Top")
		(3 "B.Mask" user "Board Geometry/Soldermask Bottom")
		(17 "Dwgs.User" user "User.Drawings")
		(19 "Cmts.User" user "User.Comments")
		(21 "Eco1.User" user "User.Eco1")
		(23 "Eco2.User" user "User.Eco2")
		(25 "Edge.Cuts" user "Board Geometry/Outline")
		(27 "Margin" user)
		(31 "F.CrtYd" user "Package Geometry/Place Bound Top")
		(29 "B.CrtYd" user "Package Geometry/Place Bound Bottom")
		(35 "F.Fab" user "Ref Des/Assembly Top")
		(33 "B.Fab" user "Ref Des/Assembly Bottom")
	)
	(footprint ""
		(layer "F.Cu")
		(at 178.7652 -153.2128)
		(property "Reference" "R467"
			(at 0 0 0)
			(layer "F.SilkS")
			(hide yes)
			(effects
				(font
					(size 1.27 1.27)
				)
			)
		)
		(property "Value" "10KR2F-2-GP"
			(at 0.064008 -3.993896 0)
			(unlocked yes)
			(layer "F.Fab")
			(hide yes)
			(effects
				(font
					(size 1.016 1.016)
					(thickness 0.1524)
				)
			)
		)
		(property "Device Type" "R402H16"
			(at 0.064008 -5.517896 0)
			(unlocked yes)
			(layer "F.Fab")
			(hide yes)
			(effects
				(font
					(size 1.016 1.016)
					(thickness 0.1524)
				)
			)
		)
		(duplicate_pad_numbers_are_jumpers no)
		(fp_line
			(start -0.508 -0.9398)
			(end -0.508 0.9398)
			(stroke
				(width 0.1524)
				(type default)
			)
			(layer "F.SilkS")
		)
		(fp_line
			(start 0.508 -0.9398)
			(end -0.508 -0.9398)
			(stroke
				(width 0.1524)
				(type default)
			)
			(layer "F.SilkS")
		)
		(fp_rect
			(start -0.508 0.9398)
			(end 0.508 -0.9398)
			(stroke
				(width 0)
				(type default)
			)
			(fill no)
			(layer "F.CrtYd")
		)
		(fp_rect
			(start -0.508 0.9398)
			(end 0.508 -0.9398)
			(stroke
				(width 0)
				(type default)
			)
			(fill no)
			(layer "F.Fab")
		)
		(pad "1" smd custom
			(at 0 -0.4445)
			(size 0.1397 0.1397)
			(layers "F.Cu" "F.Mask" "F.Paste")
			(net "P5V_STBY_VREG")
			(options
				(clearance outline)
				(anchor circle)
			)
			(primitives
				(gr_poly
					(pts
						(arc
							(start -0.1778 -0.2794)
							(mid -0.249642 -0.249642)
							(end -0.2794 -0.1778)
						)
						(arc
							(start -0.2794 0.1778)
							(mid -0.249642 0.249642)
							(end -0.1778 0.2794)
						)
						(arc
							(start 0.1778 0.2794)
							(mid 0.249642 0.249642)
							(end 0.2794 0.1778)
						)
						(arc
							(start 0.2794 -0.1778)
							(mid 0.249642 -0.249642)
							(end 0.1778 -0.2794)
						)
					)
					(width 0)
					(fill yes)
				)
			)
		)
		(pad "2" smd custom
			(at 0 0.4445)
			(size 0.1397 0.1397)
			(layers "F.Cu" "F.Mask" "F.Paste")
			(net "PWRGD_P5V_STBY")
			(options
				(clearance outline)
				(anchor circle)
			)
			(primitives
				(gr_poly
					(pts
						(arc
							(start -0.1778 -0.2794)
							(mid -0.249642 -0.249642)
							(end -0.2794 -0.1778)
						)
						(arc
							(start -0.2794 0.1778)
							(mid -0.249642 0.249642)
							(end -0.1778 0.2794)
						)
						(arc
							(start 0.1778 0.2794)
							(mid 0.249642 0.249642)
							(end 0.2794 0.1778)
						)
						(arc
							(start 0.2794 -0.1778)
							(mid 0.249642 -0.249642)
							(end 0.1778 -0.2794)
						)
					)
					(width 0)
					(fill yes)
				)
			)
		)
	)
	(footprint ""
		(layer "F.Cu")
		(at 87.3506 -48.227996 90)
		(property "Reference" "C189"
			(at 0 0 90)
			(layer "F.SilkS")
			(hide yes)
			(effects
				(font
					(size 1.27 1.27)
				)
			)
		)
		(property "Value" "SCD1U25V2KX-2-GP"
			(at 1.1811 -2.7051 90)
			(unlocked yes)
			(layer "F.Fab")
			(hide yes)
			(effects
				(font
					(size 1.016 1.016)
					(thickness 0.1524)
				)
			)
		)
		(property "Device Type" "C402H22"
			(at 1.1811 -4.2291 90)
			(unlocked yes)
			(layer "F.Fab")
			(hide yes)
			(effects
				(font
					(size 1.016 1.016)
					(thickness 0.1524)
				)
			)
		)
		(duplicate_pad_numbers_are_jumpers no)
		(fp_rect
			(start -0.4318 0.9525)
			(end 0.4318 -0.9525)
			(stroke
				(width 0)
				(type default)
			)
			(fill no)
			(layer "F.CrtYd")
		)
		(fp_rect
			(start -0.4318 0.9525)
			(end 0.4318 -0.9525)
			(stroke
				(width 0)
				(type default)
			)
			(fill no)
			(layer "F.Fab")
		)
		(pad "1" smd custom
			(at 0 -0.4445 90)
			(size 0.1524 0.1524)
			(layers "F.Cu" "F.Mask" "F.Paste")
			(net "P3V3")
			(options
				(clearance outline)
				(anchor circle)
			)
			(primitives
				(gr_poly
					(pts
						(arc
							(start 0.3048 -0.2032)
							(mid 0.275042 -0.275042)
							(end 0.2032 -0.3048)
						)
						(arc
							(start -0.2032 -0.3048)
							(mid -0.275042 -0.275042)
							(end -0.3048 -0.2032)
						)
						(arc
							(start -0.3048 0.2032)
							(mid -0.275042 0.275042)
							(end -0.2032 0.3048)
						)
						(arc
							(start 0.2032 0.3048)
							(mid 0.275042 0.275042)
							(end 0.3048 0.2032)
						)
					)
					(width 0)
					(fill yes)
				)
			)
		)
		(pad "2" smd custom
			(at 0 0.4445 90)
			(size 0.1524 0.1524)
			(layers "F.Cu" "F.Mask" "F.Paste")
			(net "GND")
			(options
				(clearance outline)
				(anchor circle)
			)
			(primitives
				(gr_poly
					(pts
						(arc
							(start 0.3048 -0.2032)
							(mid 0.275042 -0.275042)
							(end 0.2032 -0.3048)
						)
						(arc
							(start -0.2032 -0.3048)
							(mid -0.275042 -0.275042)
							(end -0.3048 -0.2032)
						)
						(arc
							(start -0.3048 0.2032)
							(mid -0.275042 0.275042)
							(end -0.2032 0.3048)
						)
						(arc
							(start 0.2032 0.3048)
							(mid 0.275042 0.275042)
							(end 0.3048 0.2032)
						)
					)
					(width 0)
					(fill yes)
				)
			)
		)
	)
	(footprint ""
		(layer "F.Cu")
		(at 63.119 -169.291 90)
		(property "Reference" "Q4"
			(at 0 0 90)
			(layer "F.SilkS")
			(hide yes)
			(effects
				(font
					(size 1.27 1.27)
				)
			)
		)
		(property "Value" "2N7002K-1-GP"
			(at 0.127 -8.9662 90)
			(unlocked yes)
			(layer "F.Fab")
			(hide yes)
			(effects
				(font
					(size 1.016 1.016)
					(thickness 0.1524)
				)
			)
		)
		(property "Device Type" "SOT23DGS2D4H44"
			(at 0.127 -10.4902 90)
			(unlocked yes)
			(layer "F.Fab")
			(hide yes)
			(effects
				(font
					(size 1.016 1.016)
					(thickness 0.1524)
				)
			)
		)
		(duplicate_pad_numbers_are_jumpers no)
		(fp_line
			(start 1.651 -1.778)
			(end -1.651 -1.778)
			(stroke
				(width 0.1524)
				(type default)
			)
			(layer "F.SilkS")
		)
		(fp_line
			(start -1.651 -1.778)
			(end -1.651 1.778)
			(stroke
				(width 0.1524)
				(type default)
			)
			(layer "F.SilkS")
		)
		(fp_line
			(start 1.651 1.778)
			(end 1.651 -1.778)
			(stroke
				(width 0.1524)
				(type default)
			)
			(layer "F.SilkS")
		)
		(fp_line
			(start -1.651 1.778)
			(end 1.651 1.778)
			(stroke
				(width 0.1524)
				(type default)
			)
			(layer "F.SilkS")
		)
		(fp_poly
			(pts
				(xy -1.778 1.8796) (xy -1.778 -1.8796) (xy 1.778 -1.8796) (xy 1.778 1.8796)
			)
			(stroke
				(width 0)
				(type default)
			)
			(fill no)
			(layer "F.CrtYd")
		)
		(fp_poly
			(pts
				(xy -1.778 1.8796) (xy -1.778 -1.8796) (xy 1.778 -1.8796) (xy 1.778 1.8796)
			)
			(stroke
				(width 0)
				(type default)
			)
			(fill no)
			(layer "F.Fab")
		)
		(pad "D" smd custom
			(at 0 -0.9525 90)
			(size 0.1905 0.1905)
			(layers "F.Cu" "F.Mask" "F.Paste")
			(net "FM_TPM_PRSNT_RST_N")
			(options
				(clearance outline)
				(anchor circle)
			)
			(primitives
				(gr_poly
					(pts
						(arc
							(start -0.1778 0.5715)
							(mid -0.321484 0.511984)
							(end -0.381 0.3683)
						)
						(arc
							(start -0.381 -0.3683)
							(mid -0.321484 -0.511984)
							(end -0.1778 -0.5715)
						)
						(arc
							(start 0.1778 -0.5715)
							(mid 0.321484 -0.511984)
							(end 0.381 -0.3683)
						)
						(arc
							(start 0.381 0.3683)
							(mid 0.321484 0.511984)
							(end 0.1778 0.5715)
						)
					)
					(width 0)
					(fill yes)
				)
			)
		)
		(pad "G" smd custom
			(at -0.98425 0.9525 90)
			(size 0.1905 0.1905)
			(layers "F.Cu" "F.Mask" "F.Paste")
			(net "Q4_G")
			(options
				(clearance outline)
				(anchor circle)
			)
			(primitives
				(gr_poly
					(pts
						(arc
							(start -0.1778 0.5715)
							(mid -0.321484 0.511984)
							(end -0.381 0.3683)
						)
						(arc
							(start -0.381 -0.3683)
							(mid -0.321484 -0.511984)
							(end -0.1778 -0.5715)
						)
						(arc
							(start 0.1778 -0.5715)
							(mid 0.321484 -0.511984)
							(end 0.381 -0.3683)
						)
						(arc
							(start 0.381 0.3683)
							(mid 0.321484 0.511984)
							(end 0.1778 0.5715)
						)
					)
					(width 0)
					(fill yes)
				)
			)
		)
		(pad "S" smd custom
			(at 0.98425 0.9525 90)
			(size 0.1905 0.1905)
			(layers "F.Cu" "F.Mask" "F.Paste")
			(net "GND")
			(options
				(clearance outline)
				(anchor circle)
			)
			(primitives
				(gr_poly
					(pts
						(arc
							(start -0.1778 0.5715)
							(mid -0.321484 0.511984)
							(end -0.381 0.3683)
						)
						(arc
							(start -0.381 -0.3683)
							(mid -0.321484 -0.511984)
							(end -0.1778 -0.5715)
						)
						(arc
							(start 0.1778 -0.5715)
							(mid 0.321484 -0.511984)
							(end 0.381 -0.3683)
						)
						(arc
							(start 0.381 0.3683)
							(mid 0.321484 0.511984)
							(end 0.1778 0.5715)
						)
					)
					(width 0)
					(fill yes)
				)
			)
		)
	)
	(footprint ""
		(layer "F.Cu")
		(at 205.794356 -126.9619 -90)
		(property "Reference" "PU7"
			(at 0 0 270)
			(layer "F.SilkS")
			(hide yes)
			(effects
				(font
					(size 1.27 1.27)
				)
			)
		)
		(property "Value" "TPS74801RGW-GP"
			(at -4.7244 -6.223 270)
			(unlocked yes)
			(layer "F.Fab")
			(hide yes)
			(effects
				(font
					(size 1.016 1.016)
					(thickness 0.1524)
				)
			)
		)
		(property "Device Type" "QFN20-1G3D15H40"
			(at -4.7244 -7.747 270)
			(unlocked yes)
			(layer "F.Fab")
			(hide yes)
			(effects
				(font
					(size 1.016 1.016)
					(thickness 0.1524)
				)
			)
		)
		(duplicate_pad_numbers_are_jumpers no)
		(fp_line
			(start -3.5179 3.5179)
			(end -2.2479 3.5179)
			(stroke
				(width 0.1524)
				(type default)
			)
			(layer "F.SilkS")
		)
		(fp_line
			(start 2.2479 3.5179)
			(end 3.5179 3.5179)
			(stroke
				(width 0.1524)
				(type default)
			)
			(layer "F.SilkS")
		)
		(fp_line
			(start 3.5179 3.5179)
			(end 3.5179 2.2479)
			(stroke
				(width 0.1524)
				(type default)
			)
			(layer "F.SilkS")
		)
		(fp_line
			(start 1.299972 3.160522)
			(end 1.299972 3.668522)
			(stroke
				(width 0.1524)
				(type default)
			)
			(layer "F.SilkS")
		)
		(fp_line
			(start -3.5179 2.2479)
			(end -3.5179 3.5179)
			(stroke
				(width 0.1524)
				(type default)
			)
			(layer "F.SilkS")
		)
		(fp_line
			(start -3.160522 1.299972)
			(end -3.922522 1.299972)
			(stroke
				(width 0.1524)
				(type default)
			)
			(layer "F.SilkS")
		)
		(fp_line
			(start 3.160522 -1.299972)
			(end 3.922522 -1.299972)
			(stroke
				(width 0.1524)
				(type default)
			)
			(layer "F.SilkS")
		)
		(fp_line
			(start -1.299972 -3.160522)
			(end -1.299972 -3.668522)
			(stroke
				(width 0.1524)
				(type default)
			)
			(layer "F.SilkS")
		)
		(fp_line
			(start -3.5179 -3.5179)
			(end -3.5179 -2.2479)
			(stroke
				(width 0.1524)
				(type default)
			)
			(layer "F.SilkS")
		)
		(fp_line
			(start -2.2479 -3.5179)
			(end -3.5179 -3.5179)
			(stroke
				(width 0.1524)
				(type default)
			)
			(layer "F.SilkS")
		)
		(fp_poly
			(pts
				(xy 3.5179 -3.5179) (xy 2.2479 -3.5179) (xy 3.5179 -2.2479)
			)
			(stroke
				(width 0)
				(type default)
			)
			(fill yes)
			(layer "F.SilkS")
		)
		(fp_rect
			(start -2.5019 2.5019)
			(end 2.5019 -2.5019)
			(stroke
				(width 0)
				(type default)
			)
			(fill no)
			(layer "F.CrtYd")
		)
		(fp_poly
			(pts
				(xy -3.5179 3.5179) (xy -3.5179 -3.5179) (xy 3.5179 -3.5179) (xy 3.5179 -2.5019) (xy -2.5019 -2.5019)
				(xy -2.5019 2.5019) (xy 2.5019 2.5019) (xy 2.5019 -2.49682) (xy 3.5179 -2.49682) (xy 3.5179 3.5179)
			)
			(stroke
				(width 0)
				(type default)
			)
			(fill no)
			(layer "F.CrtYd")
		)
		(fp_rect
			(start -3.5179 3.5179)
			(end 3.5179 -3.5179)
			(stroke
				(width 0)
				(type default)
			)
			(fill no)
			(layer "F.Fab")
		)
		(pad "1" smd rect
			(at 1.299972 -2.474722 270)
			(size 0.3556 1.0668)
			(layers "F.Cu" "F.Mask" "F.Paste")
			(net "P1V5_OUT")
		)
		(pad "2" smd rect
			(at 0.649986 -2.474722 270)
			(size 0.3556 1.0668)
			(layers "F.Cu" "F.Mask" "F.Paste")
			(net "GND")
		)
		(pad "3" smd rect
			(at 0 -2.474722 270)
			(size 0.3556 1.0668)
			(layers "F.Cu" "F.Mask" "F.Paste")
			(net "GND")
		)
		(pad "4" smd rect
			(at -0.649986 -2.474722 270)
			(size 0.3556 1.0668)
			(layers "F.Cu" "F.Mask" "F.Paste")
			(net "GND")
		)
		(pad "5" smd rect
			(at -1.299972 -2.474722 270)
			(size 0.3556 1.0668)
			(layers "F.Cu" "F.Mask" "F.Paste")
			(net "P1V8_STBY")
		)
		(pad "6" smd rect
			(at -2.474722 -1.299972 270)
			(size 1.0668 0.3556)
			(layers "F.Cu" "F.Mask" "F.Paste")
			(net "P1V8_STBY")
		)
		(pad "7" smd rect
			(at -2.474722 -0.649986 270)
			(size 1.0668 0.3556)
			(layers "F.Cu" "F.Mask" "F.Paste")
			(net "P1V8_STBY")
		)
		(pad "8" smd rect
			(at -2.474722 0 270)
			(size 1.0668 0.3556)
			(layers "F.Cu" "F.Mask" "F.Paste")
			(net "P1V8_STBY")
		)
		(pad "9" smd rect
			(at -2.474722 0.649986 270)
			(size 1.0668 0.3556)
			(layers "F.Cu" "F.Mask" "F.Paste")
			(net "PWRGD_P1V5")
		)
		(pad "10" smd rect
			(at -2.474722 1.299972 270)
			(size 1.0668 0.3556)
			(layers "F.Cu" "F.Mask" "F.Paste")
			(net "TPS74801_1V5_BIAS")
		)
		(pad "11" smd rect
			(at -1.299972 2.474722 270)
			(size 0.3556 1.0668)
			(layers "F.Cu" "F.Mask" "F.Paste")
			(net "TPS74801_1V5_EN")
		)
		(pad "12" smd rect
			(at -0.649986 2.474722 270)
			(size 0.3556 1.0668)
			(layers "F.Cu" "F.Mask" "F.Paste")
			(net "GND")
		)
		(pad "13" smd rect
			(at 0 2.474722 270)
			(size 0.3556 1.0668)
			(layers "F.Cu" "F.Mask" "F.Paste")
			(net "GND")
		)
		(pad "14" smd rect
			(at 0.649986 2.474722 270)
			(size 0.3556 1.0668)
			(layers "F.Cu" "F.Mask" "F.Paste")
			(net "GND")
		)
		(pad "15" smd rect
			(at 1.299972 2.474722 270)
			(size 0.3556 1.0668)
			(layers "F.Cu" "F.Mask" "F.Paste")
			(net "TPS74801_1V5_SS")
		)
		(pad "16" smd rect
			(at 2.474722 1.299972 270)
			(size 1.0668 0.3556)
			(layers "F.Cu" "F.Mask" "F.Paste")
			(net "TPS74801_P1V5_FB")
		)
		(pad "17" smd rect
			(at 2.474722 0.649986 270)
			(size 1.0668 0.3556)
			(layers "F.Cu" "F.Mask" "F.Paste")
			(net "GND")
		)
		(pad "18" smd rect
			(at 2.474722 0 270)
			(size 1.0668 0.3556)
			(layers "F.Cu" "F.Mask" "F.Paste")
			(net "P1V5_OUT")
		)
		(pad "19" smd rect
			(at 2.474722 -0.649986 270)
			(size 1.0668 0.3556)
			(layers "F.Cu" "F.Mask" "F.Paste")
			(net "P1V5_OUT")
		)
		(pad "20" smd rect
			(at 2.474722 -1.299972 270)
			(size 1.0668 0.3556)
			(layers "F.Cu" "F.Mask" "F.Paste")
			(net "P1V5_OUT")
		)
		(pad "21" smd rect
			(at 0 0 270)
			(size 3.2512 3.2512)
			(layers "F.Cu" "F.Mask" "F.Paste")
			(net "GND")
		)
	)
	(footprint ""
		(layer "F.Cu")
		(at 179.324 -82.931)
		(property "Reference" "R628"
			(at 0 0 0)
			(layer "F.SilkS")
			(hide yes)
			(effects
				(font
					(size 1.27 1.27)
				)
			)
		)
		(property "Value" "4K7R2F-GP"
			(at 0.064008 -3.993896 0)
			(unlocked yes)
			(layer "F.Fab")
			(hide yes)
			(effects
				(font
					(size 1.016 1.016)
					(thickness 0.1524)
				)
			)
		)
		(property "Device Type" "R402H16"
			(at 0.064008 -5.517896 0)
			(unlocked yes)
			(layer "F.Fab")
			(hide yes)
			(effects
				(font
					(size 1.016 1.016)
					(thickness 0.1524)
				)
			)
		)
		(duplicate_pad_numbers_are_jumpers no)
		(fp_line
			(start -0.508 -0.9398)
			(end -0.508 0.9398)
			(stroke
				(width 0.1524)
				(type default)
			)
			(layer "F.SilkS")
		)
		(fp_line
			(start 0.508 -0.9398)
			(end -0.508 -0.9398)
			(stroke
				(width 0.1524)
				(type default)
			)
			(layer "F.SilkS")
		)
		(fp_rect
			(start -0.508 0.9398)
			(end 0.508 -0.9398)
			(stroke
				(width 0)
				(type default)
			)
			(fill no)
			(layer "F.CrtYd")
		)
		(fp_rect
			(start -0.508 0.9398)
			(end 0.508 -0.9398)
			(stroke
				(width 0)
				(type default)
			)
			(fill no)
			(layer "F.Fab")
		)
		(pad "1" smd custom
			(at 0 -0.4445)
			(size 0.1397 0.1397)
			(layers "F.Cu" "F.Mask" "F.Paste")
			(net "P1V8")
			(options
				(clearance outline)
				(anchor circle)
			)
			(primitives
				(gr_poly
					(pts
						(arc
							(start -0.1778 -0.2794)
							(mid -0.249642 -0.249642)
							(end -0.2794 -0.1778)
						)
						(arc
							(start -0.2794 0.1778)
							(mid -0.249642 0.249642)
							(end -0.1778 0.2794)
						)
						(arc
							(start 0.1778 0.2794)
							(mid 0.249642 0.249642)
							(end 0.2794 0.1778)
						)
						(arc
							(start 0.2794 -0.1778)
							(mid 0.249642 -0.249642)
							(end 0.1778 -0.2794)
						)
					)
					(width 0)
					(fill yes)
				)
			)
		)
		(pad "2" smd custom
			(at 0 0.4445)
			(size 0.1397 0.1397)
			(layers "F.Cu" "F.Mask" "F.Paste")
			(net "SYS_HALT1#")
			(options
				(clearance outline)
				(anchor circle)
			)
			(primitives
				(gr_poly
					(pts
						(arc
							(start -0.1778 -0.2794)
							(mid -0.249642 -0.249642)
							(end -0.2794 -0.1778)
						)
						(arc
							(start -0.2794 0.1778)
							(mid -0.249642 0.249642)
							(end -0.1778 0.2794)
						)
						(arc
							(start 0.1778 0.2794)
							(mid 0.249642 0.249642)
							(end 0.2794 0.1778)
						)
						(arc
							(start 0.2794 -0.1778)
							(mid 0.249642 -0.249642)
							(end 0.1778 -0.2794)
						)
					)
					(width 0)
					(fill yes)
				)
			)
		)
	)
)
